(kicad_pcb
	(version 20260206)
	(generator "pcbnew")
	(generator_version "10.0")
	(general
		(thickness 1.6)
		(legacy_teardrops no)
	)
	(paper "A4")
	(title_block
		(title "Bryce Canyon_R.DPB_16317-1_OCP.brd")
		(comment 1 "Bryce Canyon / footprints 554-561 of 2099")
	)
	(layers
		(0 "F.Cu" signal "TOP")
		(4 "In1.Cu" signal "L2GND")
		(6 "In2.Cu" signal "L3")
		(8 "In3.Cu" signal "L4VCC")
		(10 "In4.Cu" signal "L5VCC")
		(12 "In5.Cu" signal "L6")
		(14 "In6.Cu" signal "L7GND")
		(2 "B.Cu" signal "BOTTOM")
		(9 "F.Adhes" user "F.Adhesive")
		(11 "B.Adhes" user "B.Adhesive")
		(13 "F.Paste" user "Package Geometry/Pastemask Top")
		(15 "B.Paste" user "Package Geometry/Pastemask Bottom")
		(5 "F.SilkS" user "Ref Des/Silkscreen Top")
		(7 "B.SilkS" user "Ref Des/Silkscreen Bottom")
		(1 "F.Mask" user "Board Geometry/Soldermask Top")
		(3 "B.Mask" user "Board Geometry/Soldermask Bottom")
		(17 "Dwgs.User" user "User.Drawings")
		(19 "Cmts.User" user "User.Comments")
		(21 "Eco1.User" user "User.Eco1")
		(23 "Eco2.User" user "User.Eco2")
		(25 "Edge.Cuts" user "Board Geometry/Outline")
		(27 "Margin" user)
		(31 "F.CrtYd" user "Package Geometry/Place Bound Top")
		(29 "B.CrtYd" user "Package Geometry/Place Bound Bottom")
		(35 "F.Fab" user "Ref Des/Assembly Top")
		(33 "B.Fab" user "Ref Des/Assembly Bottom")
	)
	(footprint ""
		(layer "F.Cu")
		(at 460.3242 -18.4658 -90)
		(property "Reference" "Q179"
			(at 0 0 270)
			(layer "F.SilkS")
			(hide yes)
			(effects
				(font
					(size 1.27 1.27)
				)
			)
		)
		(property "Value" "2N7002KDW-GP"
			(at -2.3622 -8.2042 270)
			(unlocked yes)
			(layer "F.Fab")
			(hide yes)
			(effects
				(font
					(size 1.016 1.016)
					(thickness 0.1524)
				)
			)
		)
		(property "Device Type" "SOT-363H44"
			(at -2.3622 -10.1092 270)
			(unlocked yes)
			(layer "F.Fab")
			(hide yes)
			(effects
				(font
					(size 1.016 1.016)
					(thickness 0.1524)
				)
			)
		)
		(duplicate_pad_numbers_are_jumpers no)
		(fp_line
			(start -1.4478 1.7018)
			(end 1.4478 1.7018)
			(stroke
				(width 0.1524)
				(type default)
			)
			(layer "F.SilkS")
		)
		(fp_line
			(start 1.4478 1.7018)
			(end 1.4478 -1.7018)
			(stroke
				(width 0.1524)
				(type default)
			)
			(layer "F.SilkS")
		)
		(fp_line
			(start -1.27 1.524)
			(end -1.27 0.6604)
			(stroke
				(width 0.4826)
				(type default)
			)
			(layer "F.SilkS")
		)
		(fp_line
			(start -1.4478 -1.7018)
			(end -1.4478 1.7018)
			(stroke
				(width 0.1524)
				(type default)
			)
			(layer "F.SilkS")
		)
		(fp_line
			(start 1.4478 -1.7018)
			(end -1.4478 -1.7018)
			(stroke
				(width 0.1524)
				(type default)
			)
			(layer "F.SilkS")
		)
		(fp_poly
			(pts
				(xy -1.524 -1.778) (xy 1.524 -1.778) (xy 1.524 1.778) (xy -1.524 1.778)
			)
			(stroke
				(width 0)
				(type default)
			)
			(fill no)
			(layer "F.CrtYd")
		)
		(fp_poly
			(pts
				(xy -1.524 -1.778) (xy 1.524 -1.778) (xy 1.524 1.778) (xy -1.524 1.778)
			)
			(stroke
				(width 0)
				(type default)
			)
			(fill no)
			(layer "F.Fab")
		)
		(pad "1" smd rect
			(at -0.65024 0.9398 270)
			(size 0.4064 1.016)
			(layers "F.Cu" "F.Mask" "F.Paste")
			(net "GND")
		)
		(pad "2" smd rect
			(at 0 0.9398 270)
			(size 0.4064 1.016)
			(layers "F.Cu" "F.Mask" "F.Paste")
			(net "SW_PWR_R_HDD34")
		)
		(pad "3" smd rect
			(at 0.65024 0.9398 270)
			(size 0.4064 1.016)
			(layers "F.Cu" "F.Mask" "F.Paste")
			(net "SW_HDD_P34")
		)
		(pad "4" smd rect
			(at 0.65024 -0.9398 270)
			(size 0.4064 1.016)
			(layers "F.Cu" "F.Mask" "F.Paste")
			(net "GND")
		)
		(pad "5" smd rect
			(at 0 -0.9398 270)
			(size 0.4064 1.016)
			(layers "F.Cu" "F.Mask" "F.Paste")
			(net "SW_HDD_G34")
		)
		(pad "6" smd rect
			(at -0.65024 -0.9398 270)
			(size 0.4064 1.016)
			(layers "F.Cu" "F.Mask" "F.Paste")
			(net "SW_HDD_R34")
		)
	)
	(footprint ""
		(layer "F.Cu")
		(at 46.355 -265.684 -90)
		(property "Reference" "C48"
			(at 0 0 270)
			(layer "F.SilkS")
			(hide yes)
			(effects
				(font
					(size 1.27 1.27)
				)
			)
		)
		(property "Value" "SC4D7U25V5KX-1-GP"
			(at -0.0762 -6.1214 270)
			(unlocked yes)
			(layer "F.Fab")
			(hide yes)
			(effects
				(font
					(size 1.016 1.016)
					(thickness 0.1524)
				)
			)
		)
		(property "Device Type" "C805H58"
			(at -0.0762 -8.1534 270)
			(unlocked yes)
			(layer "F.Fab")
			(hide yes)
			(effects
				(font
					(size 1.016 1.016)
					(thickness 0.1524)
				)
			)
		)
		(duplicate_pad_numbers_are_jumpers no)
		(fp_line
			(start 0.635 0)
			(end -0.635 0)
			(stroke
				(width 0.508)
				(type default)
			)
			(layer "F.SilkS")
		)
		(fp_rect
			(start -0.9652 1.778)
			(end 0.9652 -1.778)
			(stroke
				(width 0)
				(type default)
			)
			(fill no)
			(layer "F.CrtYd")
		)
		(fp_poly
			(pts
				(xy -0.9652 -1.778) (xy 0.9652 -1.778) (xy 0.9652 1.778) (xy -0.9652 1.778)
			)
			(stroke
				(width 0)
				(type default)
			)
			(fill no)
			(layer "F.Fab")
		)
		(pad "1" smd rect
			(at 0 -0.9652 270)
			(size 1.397 1.143)
			(layers "F.Cu" "F.Mask" "F.Paste")
			(net "P12V_HDD1")
		)
		(pad "2" smd rect
			(at 0 0.9652 270)
			(size 1.397 1.143)
			(layers "F.Cu" "F.Mask" "F.Paste")
			(net "GND")
		)
	)
	(footprint ""
		(layer "F.Cu")
		(at 129.413762 -154.70505)
		(property "Reference" "TP96"
			(at 0 0 0)
			(layer "F.SilkS")
			(hide yes)
			(effects
				(font
					(size 1.27 1.27)
				)
			)
		)
		(property "Value" "*"
			(at -0.0508 -1.6764 0)
			(unlocked yes)
			(layer "F.Fab")
			(hide yes)
			(effects
				(font
					(size 1.016 1.016)
					(thickness 0.1524)
				)
			)
		)
		(property "Device Type" "TPAD32"
			(at -0.0508 -3.2004 0)
			(unlocked yes)
			(layer "F.Fab")
			(hide yes)
			(effects
				(font
					(size 1.016 1.016)
					(thickness 0.1524)
				)
			)
		)
		(duplicate_pad_numbers_are_jumpers no)
		(fp_poly
			(pts
				(arc
					(start 0.4064 0)
					(mid -0.4064 0)
					(end 0.4064 0)
				)
			)
			(stroke
				(width 0)
				(type default)
			)
			(fill no)
			(layer "F.CrtYd")
		)
		(fp_poly
			(pts
				(arc
					(start 0.7112 0)
					(mid -0.7112 0)
					(end 0.7112 0)
				)
			)
			(stroke
				(width 0)
				(type default)
			)
			(fill no)
			(layer "F.Fab")
		)
		(pad "1" smd circle
			(at 0 0)
			(size 0.8128 0.8128)
			(layers "F.Cu" "F.Mask" "F.Paste")
			(net "ACT_HDD_15")
		)
	)
	(footprint ""
		(layer "F.Cu")
		(at 265.0617 -379.174756 -90)
		(property "Reference" "R1066"
			(at 0 0 270)
			(layer "F.SilkS")
			(hide yes)
			(effects
				(font
					(size 1.27 1.27)
				)
			)
		)
		(property "Value" "0R2J-2-GP"
			(at 0.064008 -3.993896 270)
			(unlocked yes)
			(layer "F.Fab")
			(hide yes)
			(effects
				(font
					(size 1.016 1.016)
					(thickness 0.1524)
				)
			)
		)
		(property "Device Type" "R402H16"
			(at 0.064008 -5.517896 270)
			(unlocked yes)
			(layer "F.Fab")
			(hide yes)
			(effects
				(font
					(size 1.016 1.016)
					(thickness 0.1524)
				)
			)
		)
		(duplicate_pad_numbers_are_jumpers no)
		(fp_line
			(start -0.508 -0.9398)
			(end -0.508 0.9398)
			(stroke
				(width 0.1524)
				(type default)
			)
			(layer "F.SilkS")
		)
		(fp_line
			(start 0.508 -0.9398)
			(end -0.508 -0.9398)
			(stroke
				(width 0.1524)
				(type default)
			)
			(layer "F.SilkS")
		)
		(fp_rect
			(start -0.508 0.9398)
			(end 0.508 -0.9398)
			(stroke
				(width 0)
				(type default)
			)
			(fill no)
			(layer "F.CrtYd")
		)
		(fp_rect
			(start -0.508 0.9398)
			(end 0.508 -0.9398)
			(stroke
				(width 0)
				(type default)
			)
			(fill no)
			(layer "F.Fab")
		)
		(pad "1" smd custom
			(at 0 -0.4445 270)
			(size 0.1397 0.1397)
			(layers "F.Cu" "F.Mask" "F.Paste")
			(net "IR_SWITCH_E")
			(options
				(clearance outline)
				(anchor circle)
			)
			(primitives
				(gr_poly
					(pts
						(arc
							(start -0.1778 -0.2794)
							(mid -0.249642 -0.249642)
							(end -0.2794 -0.1778)
						)
						(arc
							(start -0.2794 0.1778)
							(mid -0.249642 0.249642)
							(end -0.1778 0.2794)
						)
						(arc
							(start 0.1778 0.2794)
							(mid 0.249642 0.249642)
							(end 0.2794 0.1778)
						)
						(arc
							(start 0.2794 -0.1778)
							(mid 0.249642 -0.249642)
							(end 0.1778 -0.2794)
						)
					)
					(width 0)
					(fill yes)
				)
			)
		)
		(pad "2" smd custom
			(at 0 0.4445 270)
			(size 0.1397 0.1397)
			(layers "F.Cu" "F.Mask" "F.Paste")
			(net "DRAWER_OUT_NET")
			(options
				(clearance outline)
				(anchor circle)
			)
			(primitives
				(gr_poly
					(pts
						(arc
							(start -0.1778 -0.2794)
							(mid -0.249642 -0.249642)
							(end -0.2794 -0.1778)
						)
						(arc
							(start -0.2794 0.1778)
							(mid -0.249642 0.249642)
							(end -0.1778 0.2794)
						)
						(arc
							(start 0.1778 0.2794)
							(mid 0.249642 0.249642)
							(end 0.2794 0.1778)
						)
						(arc
							(start 0.2794 -0.1778)
							(mid 0.249642 -0.249642)
							(end 0.1778 -0.2794)
						)
					)
					(width 0)
					(fill yes)
				)
			)
		)
	)
	(footprint ""
		(layer "F.Cu")
		(at 32.463486 -130.21945 90)
		(property "Reference" "C184"
			(at 0 0 90)
			(layer "F.SilkS")
			(hide yes)
			(effects
				(font
					(size 1.27 1.27)
				)
			)
		)
		(property "Value" "SCD01U16V1KX-GP"
			(at -2.8321 -1.7399 90)
			(unlocked yes)
			(layer "F.Fab")
			(hide yes)
			(effects
				(font
					(size 1.016 1.016)
					(thickness 0.1524)
				)
			)
		)
		(property "Device Type" "C0201H13"
			(at -2.8321 -3.2639 90)
			(unlocked yes)
			(layer "F.Fab")
			(hide yes)
			(effects
				(font
					(size 1.016 1.016)
					(thickness 0.1524)
				)
			)
		)
		(duplicate_pad_numbers_are_jumpers no)
		(fp_rect
			(start -0.2794 0.6477)
			(end 0.2794 -0.6477)
			(stroke
				(width 0)
				(type default)
			)
			(fill no)
			(layer "F.CrtYd")
		)
		(fp_rect
			(start -0.2794 0.6477)
			(end 0.2794 -0.6477)
			(stroke
				(width 0)
				(type default)
			)
			(fill no)
			(layer "F.Fab")
		)
		(pad "1" smd custom
			(at 0 -0.2794 90)
			(size 0.0762 0.0762)
			(layers "F.Cu" "F.Mask" "F.Paste")
			(net "SAS_HDD_RX_N12")
			(options
				(clearance outline)
				(anchor circle)
			)
			(primitives
				(gr_poly
					(pts
						(arc
							(start 0.1524 -0.127)
							(mid 0.137521 -0.162921)
							(end 0.1016 -0.1778)
						)
						(arc
							(start -0.1016 -0.1778)
							(mid -0.137521 -0.162921)
							(end -0.1524 -0.127)
						)
						(arc
							(start -0.1524 0.127)
							(mid -0.137521 0.162921)
							(end -0.1016 0.1778)
						)
						(arc
							(start 0.1016 0.1778)
							(mid 0.137521 0.162921)
							(end 0.1524 0.127)
						)
					)
					(width 0)
					(fill yes)
				)
			)
		)
		(pad "2" smd custom
			(at 0 0.2794 90)
			(size 0.0762 0.0762)
			(layers "F.Cu" "F.Mask" "F.Paste")
			(net "PHY_SCC_B_TO_DRV_B_12_DN")
			(options
				(clearance outline)
				(anchor circle)
			)
			(primitives
				(gr_poly
					(pts
						(arc
							(start 0.1524 -0.127)
							(mid 0.137521 -0.162921)
							(end 0.1016 -0.1778)
						)
						(arc
							(start -0.1016 -0.1778)
							(mid -0.137521 -0.162921)
							(end -0.1524 -0.127)
						)
						(arc
							(start -0.1524 0.127)
							(mid -0.137521 0.162921)
							(end -0.1016 0.1778)
						)
						(arc
							(start 0.1016 0.1778)
							(mid 0.137521 0.162921)
							(end 0.1524 0.127)
						)
					)
					(width 0)
					(fill yes)
				)
			)
		)
	)
	(footprint ""
		(layer "F.Cu")
		(at 265.586972 -355.444806 90)
		(property "Reference" "R1056"
			(at 0 0 90)
			(layer "F.SilkS")
			(hide yes)
			(effects
				(font
					(size 1.27 1.27)
				)
			)
		)
		(property "Value" "0R5J-5-GP"
			(at 0 -8.9535 90)
			(unlocked yes)
			(layer "F.Fab")
			(hide yes)
			(effects
				(font
					(size 1.27 1.016)
					(thickness 0.1524)
				)
			)
		)
		(property "Device Type" "R805H24"
			(at 0 -10.6299 90)
			(unlocked yes)
			(layer "F.Fab")
			(hide yes)
			(effects
				(font
					(size 1.27 1.016)
					(thickness 0.1524)
				)
			)
		)
		(duplicate_pad_numbers_are_jumpers no)
		(fp_line
			(start 0.889 -1.7018)
			(end -0.889 -1.7018)
			(stroke
				(width 0.1524)
				(type default)
			)
			(layer "F.SilkS")
		)
		(fp_line
			(start 0.889 -1.7018)
			(end 0.889 -0.381)
			(stroke
				(width 0.1524)
				(type default)
			)
			(layer "F.SilkS")
		)
		(fp_line
			(start -0.889 -1.7018)
			(end -0.889 0.2794)
			(stroke
				(width 0.1524)
				(type default)
			)
			(layer "F.SilkS")
		)
		(fp_line
			(start -0.889 0.0762)
			(end -0.889 1.7018)
			(stroke
				(width 0.1524)
				(type default)
			)
			(layer "F.SilkS")
		)
		(fp_line
			(start 0.889 1.7018)
			(end 0.889 -0.508)
			(stroke
				(width 0.1524)
				(type default)
			)
			(layer "F.SilkS")
		)
		(fp_line
			(start -0.889 1.7018)
			(end 0.889 1.7018)
			(stroke
				(width 0.1524)
				(type default)
			)
			(layer "F.SilkS")
		)
		(fp_poly
			(pts
				(xy 0.9652 -1.778) (xy 0.9652 1.778) (xy -0.9652 1.778) (xy -0.9652 -1.778)
			)
			(stroke
				(width 0)
				(type default)
			)
			(fill no)
			(layer "F.CrtYd")
		)
		(fp_rect
			(start -0.9652 1.778)
			(end 0.9652 -1.778)
			(stroke
				(width 0)
				(type default)
			)
			(fill no)
			(layer "F.Fab")
		)
		(pad "1" smd rect
			(at 0 -0.9652 90)
			(size 1.397 1.143)
			(layers "F.Cu" "F.Mask" "F.Paste")
			(net "MB3_CM_GATE")
		)
		(pad "2" smd rect
			(at 0 0.9652 90)
			(size 1.397 1.143)
			(layers "F.Cu" "F.Mask" "F.Paste")
			(net "MB3_CM_GATE_R")
		)
	)
	(footprint ""
		(layer "F.Cu")
		(at 16.891 -247.65 180)
		(property "Reference" "D36"
			(at 0 0 180)
			(layer "F.SilkS")
			(hide yes)
			(effects
				(font
					(size 1.27 1.27)
				)
			)
		)
		(property "Value" "RB551V30-GP"
			(at 0 -6.7818 180)
			(unlocked yes)
			(layer "F.Fab")
			(hide yes)
			(effects
				(font
					(size 1.016 1.016)
					(thickness 0.1524)
				)
			)
		)
		(property "Device Type" "SOD323AKH38"
			(at 0 -8.6868 180)
			(unlocked yes)
			(layer "F.Fab")
			(hide yes)
			(effects
				(font
					(size 1.016 1.016)
					(thickness 0.1524)
				)
			)
		)
		(duplicate_pad_numbers_are_jumpers no)
		(fp_line
			(start 0.889 2.159)
			(end -0.889 2.159)
			(stroke
				(width 0.1524)
				(type default)
			)
			(layer "F.SilkS")
		)
		(fp_line
			(start 0.889 -1.9304)
			(end 0.889 2.159)
			(stroke
				(width 0.1524)
				(type default)
			)
			(layer "F.SilkS")
		)
		(fp_line
			(start 0.762 2.0574)
			(end -0.762 2.0574)
			(stroke
				(width 0.508)
				(type default)
			)
			(layer "F.SilkS")
		)
		(fp_line
			(start -0.889 2.159)
			(end -0.889 -1.9304)
			(stroke
				(width 0.1524)
				(type default)
			)
			(layer "F.SilkS")
		)
		(fp_line
			(start -0.889 -1.9304)
			(end 0.889 -1.9304)
			(stroke
				(width 0.1524)
				(type default)
			)
			(layer "F.SilkS")
		)
		(fp_rect
			(start -1.016 2.3114)
			(end 1.016 -2.0066)
			(stroke
				(width 0)
				(type default)
			)
			(fill no)
			(layer "F.CrtYd")
		)
		(fp_poly
			(pts
				(xy -1.016 -2.0066) (xy 1.016 -2.0066) (xy 1.016 2.3114) (xy -1.016 2.3114)
			)
			(stroke
				(width 0)
				(type default)
			)
			(fill no)
			(layer "F.Fab")
		)
		(pad "A" smd rect
			(at 0 -1.143 180)
			(size 0.5588 1.016)
			(layers "F.Cu" "F.Mask" "F.Paste")
			(net "SW_HDD_R0")
		)
		(pad "K" smd rect
			(at 0 1.143 180)
			(size 0.5588 1.016)
			(layers "F.Cu" "F.Mask" "F.Paste")
			(net "SW_HDD_N0")
		)
	)
	(footprint ""
		(layer "F.Cu")
		(at 14.732 -265.684 -90)
		(property "Reference" "C502"
			(at 0 0 270)
			(layer "F.SilkS")
			(hide yes)
			(effects
				(font
					(size 1.27 1.27)
				)
			)
		)
		(property "Value" "SC4D7U25V5KX-1-GP"
			(at -0.0762 -6.1214 270)
			(unlocked yes)
			(layer "F.Fab")
			(hide yes)
			(effects
				(font
					(size 1.016 1.016)
					(thickness 0.1524)
				)
			)
		)
		(property "Device Type" "C805H58"
			(at -0.0762 -8.1534 270)
			(unlocked yes)
			(layer "F.Fab")
			(hide yes)
			(effects
				(font
					(size 1.016 1.016)
					(thickness 0.1524)
				)
			)
		)
		(duplicate_pad_numbers_are_jumpers no)
		(fp_line
			(start 0.635 0)
			(end -0.635 0)
			(stroke
				(width 0.508)
				(type default)
			)
			(layer "F.SilkS")
		)
		(fp_rect
			(start -0.9652 1.778)
			(end 0.9652 -1.778)
			(stroke
				(width 0)
				(type default)
			)
			(fill no)
			(layer "F.CrtYd")
		)
		(fp_poly
			(pts
				(xy -0.9652 -1.778) (xy 0.9652 -1.778) (xy 0.9652 1.778) (xy -0.9652 1.778)
			)
			(stroke
				(width 0)
				(type default)
			)
			(fill no)
			(layer "F.Fab")
		)
		(pad "1" smd rect
			(at 0 -0.9652 270)
			(size 1.397 1.143)
			(layers "F.Cu" "F.Mask" "F.Paste")
			(net "P12V_HDD0")
		)
		(pad "2" smd rect
			(at 0 0.9652 270)
			(size 1.397 1.143)
			(layers "F.Cu" "F.Mask" "F.Paste")
			(net "GND")
		)
	)
)
